# S9S_MB_2U (Grand Teton) — schematic netlist excerpt (pin names and nets, part order shuffled) for the footprints in the layout excerpt that follows; sources: Cadence DE-HDL packaged netlist, KiCad conversion of 03242023_DA0F0TMBIJ0_F0T_Motherboard_J_brd_V01_OCP.brd

C291  Q_CAP  22UF 4V 20% X6S  pkg C0402  page 77 : A = PVCCIN_CPU1 ; B = GND
PC2222  Q_CAP  1UF 25V 10% X6S  pkg C0402  page 300 : A = PVNN_MAIN_CPU1_VCC ; B = GND

(kicad_pcb
	(version 20260206)
	(generator "pcbnew")
	(generator_version "10.0")
	(general
		(thickness 1.6)
		(legacy_teardrops no)
	)
	(paper "A4")
	(title_block
		(title "03242023_DA0F0TMBIJ0_F0T_Motherboard_J_brd_V01_OCP.brd")
		(comment 1 "Grand Teton / footprints 3581-3582 of 6105")
	)
	(layers
		(0 "F.Cu" signal "TOP")
		(4 "In1.Cu" signal "GND")
		(6 "In2.Cu" signal "IN1")
		(8 "In3.Cu" signal "GND1")
		(10 "In4.Cu" signal "IN2")
		(12 "In5.Cu" signal "GND2")
		(14 "In6.Cu" signal "IN3")
		(16 "In7.Cu" signal "GND3")
		(18 "In8.Cu" signal "VCC")
		(20 "In9.Cu" signal "VCC1")
		(22 "In10.Cu" signal "GND4")
		(24 "In11.Cu" signal "IN4")
		(26 "In12.Cu" signal "GND5")
		(28 "In13.Cu" signal "IN5")
		(30 "In14.Cu" signal "GND6")
		(32 "In15.Cu" signal "IN6")
		(34 "In16.Cu" signal "GND7")
		(2 "B.Cu" signal "BOTTOM")
		(9 "F.Adhes" user "F.Adhesive")
		(11 "B.Adhes" user "B.Adhesive")
		(13 "F.Paste" user "Package Geometry/Pastemask Top")
		(15 "B.Paste" user "Package Geometry/Pastemask Bottom")
		(5 "F.SilkS" user "Ref Des/Silkscreen Top")
		(7 "B.SilkS" user "Ref Des/Silkscreen Bottom")
		(1 "F.Mask" user "Board Geometry/Soldermask Top")
		(3 "B.Mask" user "Board Geometry/Soldermask Bottom")
		(17 "Dwgs.User" user "User.Drawings")
		(19 "Cmts.User" user "User.Comments")
		(21 "Eco1.User" user "User.Eco1")
		(23 "Eco2.User" user "User.Eco2")
		(25 "Edge.Cuts" user "Board Geometry/Outline")
		(27 "Margin" user)
		(31 "F.CrtYd" user "Package Geometry/Place Bound Top")
		(29 "B.CrtYd" user "Package Geometry/Place Bound Bottom")
		(35 "F.Fab" user "Ref Des/Assembly Top")
		(33 "B.Fab" user "Ref Des/Assembly Bottom")
	)
	(footprint ""
		(layer "F.Cu")
		(at 22.86889 -182.595266 180)
		(property "Reference" "PC2222"
			(at 0 0 180)
			(layer "F.SilkS")
			(hide yes)
			(effects
				(font
					(size 1.27 1.27)
				)
			)
		)
		(property "Value" ""
			(at 0 0 180)
			(layer "F.Fab")
			(effects
				(font
					(size 1.27 1.27)
				)
			)
		)
		(duplicate_pad_numbers_are_jumpers no)
		(fp_line
			(start 0.7874 0.4064)
			(end -0.7874 0.4064)
			(stroke
				(width 0.1524)
				(type default)
			)
			(layer "F.SilkS")
		)
		(fp_line
			(start 0.7874 -0.4064)
			(end 0.7874 0.4064)
			(stroke
				(width 0.1524)
				(type default)
			)
			(layer "F.SilkS")
		)
		(fp_line
			(start -0.7874 0.4064)
			(end -0.7874 -0.4064)
			(stroke
				(width 0.1524)
				(type default)
			)
			(layer "F.SilkS")
		)
		(fp_line
			(start -0.7874 -0.4064)
			(end 0.7874 -0.4064)
			(stroke
				(width 0.1524)
				(type default)
			)
			(layer "F.SilkS")
		)
		(fp_line
			(start 0.67945 0.3048)
			(end 0.120396 0.3048)
			(stroke
				(width 0.1)
				(type default)
			)
			(layer "F.Fab")
		)
		(fp_line
			(start 0.67945 -0.3048)
			(end 0.67945 0.3048)
			(stroke
				(width 0.1)
				(type default)
			)
			(layer "F.Fab")
		)
		(fp_line
			(start 0.12065 -0.2794)
			(end 0.12065 -0.3048)
			(stroke
				(width 0.1)
				(type default)
			)
			(layer "F.Fab")
		)
		(fp_line
			(start 0.12065 -0.3048)
			(end 0.67945 -0.3048)
			(stroke
				(width 0.1)
				(type default)
			)
			(layer "F.Fab")
		)
		(fp_line
			(start 0.120396 0.3048)
			(end 0.120396 0.2794)
			(stroke
				(width 0.1)
				(type default)
			)
			(layer "F.Fab")
		)
		(fp_line
			(start 0.120396 0.2794)
			(end -0.12065 0.2794)
			(stroke
				(width 0.1)
				(type default)
			)
			(layer "F.Fab")
		)
		(fp_line
			(start -0.12065 0.3048)
			(end -0.67945 0.3048)
			(stroke
				(width 0.1)
				(type default)
			)
			(layer "F.Fab")
		)
		(fp_line
			(start -0.12065 0.2794)
			(end -0.12065 0.3048)
			(stroke
				(width 0.1)
				(type default)
			)
			(layer "F.Fab")
		)
		(fp_line
			(start -0.12065 -0.2794)
			(end 0.12065 -0.2794)
			(stroke
				(width 0.1)
				(type default)
			)
			(layer "F.Fab")
		)
		(fp_line
			(start -0.12065 -0.305054)
			(end -0.12065 -0.2794)
			(stroke
				(width 0.1)
				(type default)
			)
			(layer "F.Fab")
		)
		(fp_line
			(start -0.67945 0.3048)
			(end -0.67945 -0.305054)
			(stroke
				(width 0.1)
				(type default)
			)
			(layer "F.Fab")
		)
		(fp_line
			(start -0.67945 -0.305054)
			(end -0.12065 -0.305054)
			(stroke
				(width 0.1)
				(type default)
			)
			(layer "F.Fab")
		)
		(pad "1" smd circle
			(at -0.40005 0 180)
			(size 0 0)
			(layers "F.Cu" "F.Mask" "F.Paste")
			(net "PVNN_MAIN_CPU1_VCC")
		)
		(pad "2" smd circle
			(at 0.40005 0 180)
			(size 0 0)
			(layers "F.Cu" "F.Mask" "F.Paste")
			(net "GND")
		)
	)
	(footprint ""
		(layer "F.Cu")
		(at 107.2896 -251.375672 90)
		(property "Reference" "C291"
			(at 0 0 90)
			(layer "F.SilkS")
			(hide yes)
			(effects
				(font
					(size 1.27 1.27)
				)
			)
		)
		(property "Value" ""
			(at 0 0 90)
			(layer "F.Fab")
			(effects
				(font
					(size 1.27 1.27)
				)
			)
		)
		(duplicate_pad_numbers_are_jumpers no)
		(fp_line
			(start 0.7874 -0.4064)
			(end 0.7874 0.4064)
			(stroke
				(width 0.1524)
				(type default)
			)
			(layer "F.SilkS")
		)
		(fp_line
			(start -0.7874 -0.4064)
			(end 0.7874 -0.4064)
			(stroke
				(width 0.1524)
				(type default)
			)
			(layer "F.SilkS")
		)
		(fp_line
			(start 0.7874 0.4064)
			(end -0.7874 0.4064)
			(stroke
				(width 0.1524)
				(type default)
			)
			(layer "F.SilkS")
		)
		(fp_line
			(start -0.7874 0.4064)
			(end -0.7874 -0.4064)
			(stroke
				(width 0.1524)
				(type default)
			)
			(layer "F.SilkS")
		)
		(fp_line
			(start -0.12065 -0.305054)
			(end -0.12065 -0.2794)
			(stroke
				(width 0.1)
				(type default)
			)
			(layer "F.Fab")
		)
		(fp_line
			(start -0.67945 -0.305054)
			(end -0.12065 -0.305054)
			(stroke
				(width 0.1)
				(type default)
			)
			(layer "F.Fab")
		)
		(fp_line
			(start 0.67945 -0.3048)
			(end 0.67945 0.3048)
			(stroke
				(width 0.1)
				(type default)
			)
			(layer "F.Fab")
		)
		(fp_line
			(start 0.12065 -0.3048)
			(end 0.67945 -0.3048)
			(stroke
				(width 0.1)
				(type default)
			)
			(layer "F.Fab")
		)
		(fp_line
			(start 0.12065 -0.2794)
			(end 0.12065 -0.3048)
			(stroke
				(width 0.1)
				(type default)
			)
			(layer "F.Fab")
		)
		(fp_line
			(start -0.12065 -0.2794)
			(end 0.12065 -0.2794)
			(stroke
				(width 0.1)
				(type default)
			)
			(layer "F.Fab")
		)
		(fp_line
			(start 0.120396 0.2794)
			(end -0.12065 0.2794)
			(stroke
				(width 0.1)
				(type default)
			)
			(layer "F.Fab")
		)
		(fp_line
			(start -0.12065 0.2794)
			(end -0.12065 0.3048)
			(stroke
				(width 0.1)
				(type default)
			)
			(layer "F.Fab")
		)
		(fp_line
			(start 0.67945 0.3048)
			(end 0.120396 0.3048)
			(stroke
				(width 0.1)
				(type default)
			)
			(layer "F.Fab")
		)
		(fp_line
			(start 0.120396 0.3048)
			(end 0.120396 0.2794)
			(stroke
				(width 0.1)
				(type default)
			)
			(layer "F.Fab")
		)
		(fp_line
			(start -0.12065 0.3048)
			(end -0.67945 0.3048)
			(stroke
				(width 0.1)
				(type default)
			)
			(layer "F.Fab")
		)
		(fp_line
			(start -0.67945 0.3048)
			(end -0.67945 -0.305054)
			(stroke
				(width 0.1)
				(type default)
			)
			(layer "F.Fab")
		)
		(pad "1" smd circle
			(at -0.40005 0 90)
			(size 0 0)
			(layers "F.Cu" "F.Mask" "F.Paste")
			(net "PVCCIN_CPU1")
		)
		(pad "2" smd circle
			(at 0.40005 0 90)
			(size 0 0)
			(layers "F.Cu" "F.Mask" "F.Paste")
			(net "GND")
		)
	)
)
